(kicad_pcb
	(version 20260206)
	(generator "pcbnew")
	(generator_version "10.0")
	(general
		(thickness 1.6)
		(legacy_teardrops no)
	)
	(paper "A4")
	(title_block
		(title "pdpb — Lightning_PDPB_BRD.brd")
		(comment 1 "Lightning (Wiwynn / Facebook NVMe JBOF) / footprints 379-386 of 1140")
	)
	(layers
		(0 "F.Cu" signal "TOP")
		(4 "In1.Cu" signal "L2GND")
		(6 "In2.Cu" signal "L3")
		(8 "In3.Cu" signal "L4VCC")
		(10 "In4.Cu" signal "L5VCC")
		(12 "In5.Cu" signal "L6")
		(14 "In6.Cu" signal "L7GND")
		(2 "B.Cu" signal "BOTTOM")
		(9 "F.Adhes" user "F.Adhesive")
		(11 "B.Adhes" user "B.Adhesive")
		(13 "F.Paste" user "Package Geometry/Pastemask Top")
		(15 "B.Paste" user "Package Geometry/Pastemask Bottom")
		(5 "F.SilkS" user "Ref Des/Silkscreen Top")
		(7 "B.SilkS" user "Ref Des/Silkscreen Bottom")
		(1 "F.Mask" user "Board Geometry/Soldermask Top")
		(3 "B.Mask" user "Board Geometry/Soldermask Bottom")
		(17 "Dwgs.User" user "User.Drawings")
		(19 "Cmts.User" user "User.Comments")
		(21 "Eco1.User" user "User.Eco1")
		(23 "Eco2.User" user "User.Eco2")
		(25 "Edge.Cuts" user "Board Geometry/Outline")
		(27 "Margin" user)
		(31 "F.CrtYd" user "Package Geometry/Place Bound Top")
		(29 "B.CrtYd" user "Package Geometry/Place Bound Bottom")
		(35 "F.Fab" user "Ref Des/Assembly Top")
		(33 "B.Fab" user "Ref Des/Assembly Bottom")
	)
	(footprint ""
		(layer "F.Cu")
		(at 43.2816 -402.7678)
		(property "Reference" "R9251"
			(at 0 0 0)
			(layer "F.SilkS")
			(hide yes)
			(effects
				(font
					(size 1.27 1.27)
				)
			)
		)
		(property "Value" "2R2010F-GP"
			(at 0.0762 -4.5466 0)
			(unlocked yes)
			(layer "F.Fab")
			(hide yes)
			(effects
				(font
					(size 1.016 1.016)
					(thickness 0.1524)
				)
			)
		)
		(property "Device Type" "R2010H26"
			(at 0.0762 -6.1468 0)
			(unlocked yes)
			(layer "F.Fab")
			(hide yes)
			(effects
				(font
					(size 1.016 1.016)
					(thickness 0.1524)
				)
			)
		)
		(duplicate_pad_numbers_are_jumpers no)
		(fp_line
			(start -3.302 -1.651)
			(end -3.302 1.651)
			(stroke
				(width 0.1524)
				(type default)
			)
			(layer "F.SilkS")
		)
		(fp_line
			(start -3.302 1.651)
			(end 3.302 1.651)
			(stroke
				(width 0.1524)
				(type default)
			)
			(layer "F.SilkS")
		)
		(fp_line
			(start 3.302 -1.651)
			(end -3.302 -1.651)
			(stroke
				(width 0.1524)
				(type default)
			)
			(layer "F.SilkS")
		)
		(fp_line
			(start 3.302 1.651)
			(end 3.302 -1.651)
			(stroke
				(width 0.1524)
				(type default)
			)
			(layer "F.SilkS")
		)
		(fp_rect
			(start -3.3782 1.7272)
			(end 3.3782 -1.7272)
			(stroke
				(width 0)
				(type default)
			)
			(fill no)
			(layer "F.CrtYd")
		)
		(fp_poly
			(pts
				(xy 3.3782 -1.7272) (xy -3.3782 -1.7272) (xy -3.3782 1.7272) (xy 3.3782 1.7272)
			)
			(stroke
				(width 0)
				(type default)
			)
			(fill no)
			(layer "F.Fab")
		)
		(pad "1" smd rect
			(at -2.3495 0)
			(size 1.143 2.794)
			(layers "F.Cu" "F.Mask" "F.Paste")
			(net "P12V_SSD6")
		)
		(pad "2" smd rect
			(at 2.3495 0)
			(size 1.143 2.794)
			(layers "F.Cu" "F.Mask" "F.Paste")
			(net "12V_PRECH_SSD6")
		)
	)
	(footprint ""
		(layer "F.Cu")
		(at 93.599 -218.44 180)
		(property "Reference" "C9428"
			(at 0 0 180)
			(layer "F.SilkS")
			(hide yes)
			(effects
				(font
					(size 1.27 1.27)
				)
			)
		)
		(property "Value" "SCD1U16V2KX-3GP"
			(at 1.1811 -2.7051 180)
			(unlocked yes)
			(layer "F.Fab")
			(hide yes)
			(effects
				(font
					(size 1.016 1.016)
					(thickness 0.1524)
				)
			)
		)
		(property "Device Type" "C402H22"
			(at 1.1811 -4.2291 180)
			(unlocked yes)
			(layer "F.Fab")
			(hide yes)
			(effects
				(font
					(size 1.016 1.016)
					(thickness 0.1524)
				)
			)
		)
		(duplicate_pad_numbers_are_jumpers no)
		(fp_rect
			(start -0.4318 0.9525)
			(end 0.4318 -0.9525)
			(stroke
				(width 0)
				(type default)
			)
			(fill no)
			(layer "F.CrtYd")
		)
		(fp_rect
			(start -0.4318 0.9525)
			(end 0.4318 -0.9525)
			(stroke
				(width 0)
				(type default)
			)
			(fill no)
			(layer "F.Fab")
		)
		(pad "1" smd custom
			(at 0 -0.4445 180)
			(size 0.1524 0.1524)
			(layers "F.Cu" "F.Mask" "F.Paste")
			(net "VDD_DIFF_3")
			(options
				(clearance outline)
				(anchor circle)
			)
			(primitives
				(gr_poly
					(pts
						(arc
							(start 0.3048 -0.2032)
							(mid 0.275042 -0.275042)
							(end 0.2032 -0.3048)
						)
						(arc
							(start -0.2032 -0.3048)
							(mid -0.275042 -0.275042)
							(end -0.3048 -0.2032)
						)
						(arc
							(start -0.3048 0.2032)
							(mid -0.275042 0.275042)
							(end -0.2032 0.3048)
						)
						(arc
							(start 0.2032 0.3048)
							(mid 0.275042 0.275042)
							(end 0.3048 0.2032)
						)
					)
					(width 0)
					(fill yes)
				)
			)
		)
		(pad "2" smd custom
			(at 0 0.4445 180)
			(size 0.1524 0.1524)
			(layers "F.Cu" "F.Mask" "F.Paste")
			(net "GND")
			(options
				(clearance outline)
				(anchor circle)
			)
			(primitives
				(gr_poly
					(pts
						(arc
							(start 0.3048 -0.2032)
							(mid 0.275042 -0.275042)
							(end 0.2032 -0.3048)
						)
						(arc
							(start -0.2032 -0.3048)
							(mid -0.275042 -0.275042)
							(end -0.3048 -0.2032)
						)
						(arc
							(start -0.3048 0.2032)
							(mid -0.275042 0.275042)
							(end -0.2032 0.3048)
						)
						(arc
							(start 0.2032 0.3048)
							(mid 0.275042 0.275042)
							(end 0.3048 0.2032)
						)
					)
					(width 0)
					(fill yes)
				)
			)
		)
	)
	(footprint ""
		(layer "F.Cu")
		(at 209.423 -44.704 180)
		(property "Reference" "R329"
			(at 0 0 180)
			(layer "F.SilkS")
			(hide yes)
			(effects
				(font
					(size 1.27 1.27)
				)
			)
		)
		(property "Value" "4K7R2J-2-GP"
			(at 0.064008 -3.993896 180)
			(unlocked yes)
			(layer "F.Fab")
			(hide yes)
			(effects
				(font
					(size 1.016 1.016)
					(thickness 0.1524)
				)
			)
		)
		(property "Device Type" "R402H16"
			(at 0.064008 -5.517896 180)
			(unlocked yes)
			(layer "F.Fab")
			(hide yes)
			(effects
				(font
					(size 1.016 1.016)
					(thickness 0.1524)
				)
			)
		)
		(duplicate_pad_numbers_are_jumpers no)
		(fp_line
			(start 0.508 -0.9398)
			(end -0.508 -0.9398)
			(stroke
				(width 0.1524)
				(type default)
			)
			(layer "F.SilkS")
		)
		(fp_line
			(start -0.508 -0.9398)
			(end -0.508 0.9398)
			(stroke
				(width 0.1524)
				(type default)
			)
			(layer "F.SilkS")
		)
		(fp_rect
			(start -0.508 0.9398)
			(end 0.508 -0.9398)
			(stroke
				(width 0)
				(type default)
			)
			(fill no)
			(layer "F.CrtYd")
		)
		(fp_rect
			(start -0.508 0.9398)
			(end 0.508 -0.9398)
			(stroke
				(width 0)
				(type default)
			)
			(fill no)
			(layer "F.Fab")
		)
		(pad "1" smd custom
			(at 0 -0.4445 180)
			(size 0.1397 0.1397)
			(layers "F.Cu" "F.Mask" "F.Paste")
			(net "P3V3")
			(options
				(clearance outline)
				(anchor circle)
			)
			(primitives
				(gr_poly
					(pts
						(arc
							(start -0.1778 -0.2794)
							(mid -0.249642 -0.249642)
							(end -0.2794 -0.1778)
						)
						(arc
							(start -0.2794 0.1778)
							(mid -0.249642 0.249642)
							(end -0.1778 0.2794)
						)
						(arc
							(start 0.1778 0.2794)
							(mid 0.249642 0.249642)
							(end 0.2794 0.1778)
						)
						(arc
							(start 0.2794 -0.1778)
							(mid 0.249642 -0.249642)
							(end 0.1778 -0.2794)
						)
					)
					(width 0)
					(fill yes)
				)
			)
		)
		(pad "2" smd custom
			(at 0 0.4445 180)
			(size 0.1397 0.1397)
			(layers "F.Cu" "F.Mask" "F.Paste")
			(net "I2C_B_TMP3_A1")
			(options
				(clearance outline)
				(anchor circle)
			)
			(primitives
				(gr_poly
					(pts
						(arc
							(start -0.1778 -0.2794)
							(mid -0.249642 -0.249642)
							(end -0.2794 -0.1778)
						)
						(arc
							(start -0.2794 0.1778)
							(mid -0.249642 0.249642)
							(end -0.1778 0.2794)
						)
						(arc
							(start 0.1778 0.2794)
							(mid 0.249642 0.249642)
							(end 0.2794 0.1778)
						)
						(arc
							(start 0.2794 -0.1778)
							(mid 0.249642 -0.249642)
							(end 0.1778 -0.2794)
						)
					)
					(width 0)
					(fill yes)
				)
			)
		)
	)
	(footprint ""
		(layer "F.Cu")
		(at 220.0148 -292.481)
		(property "Reference" "PC1191"
			(at 0 0 0)
			(layer "F.SilkS")
			(hide yes)
			(effects
				(font
					(size 1.27 1.27)
				)
			)
		)
		(property "Value" "SC22U25V6KX-GP-U"
			(at -2.860802 -5.279644 0)
			(unlocked yes)
			(layer "F.Fab")
			(hide yes)
			(effects
				(font
					(size 1.016 1.016)
					(thickness 0.1524)
				)
			)
		)
		(property "Device Type" "C1206-TO0D3H75"
			(at -2.860802 -6.803644 0)
			(unlocked yes)
			(layer "F.Fab")
			(hide yes)
			(effects
				(font
					(size 1.016 1.016)
					(thickness 0.1524)
				)
			)
		)
		(duplicate_pad_numbers_are_jumpers no)
		(fp_line
			(start -1.3081 -2.3749)
			(end 1.3081 -2.3749)
			(stroke
				(width 0.1524)
				(type default)
			)
			(layer "F.SilkS")
		)
		(fp_line
			(start -1.3081 2.3749)
			(end -1.3081 -2.3749)
			(stroke
				(width 0.1524)
				(type default)
			)
			(layer "F.SilkS")
		)
		(fp_line
			(start 1.3081 -2.3749)
			(end 1.3081 2.3749)
			(stroke
				(width 0.1524)
				(type default)
			)
			(layer "F.SilkS")
		)
		(fp_line
			(start 1.3081 2.3749)
			(end -1.3081 2.3749)
			(stroke
				(width 0.1524)
				(type default)
			)
			(layer "F.SilkS")
		)
		(fp_rect
			(start -0.8001 1.6002)
			(end 0.8001 -1.6002)
			(stroke
				(width 0)
				(type default)
			)
			(fill no)
			(layer "F.CrtYd")
		)
		(fp_poly
			(pts
				(xy -1.5621 2.4511) (xy -1.5621 1.6002) (xy 0.8001 1.6002) (xy 0.8001 -1.6002) (xy -0.8001 -1.6002)
				(xy -0.8001 1.5875) (xy -1.5621 1.5875) (xy -1.5621 -2.4511) (xy 1.5621 -2.4511) (xy 1.5621 2.4511)
			)
			(stroke
				(width 0)
				(type default)
			)
			(fill no)
			(layer "F.CrtYd")
		)
		(fp_rect
			(start -1.5621 2.4511)
			(end 1.5621 -2.4511)
			(stroke
				(width 0)
				(type default)
			)
			(fill no)
			(layer "F.Fab")
		)
		(pad "1" smd rect
			(at 0 -1.392936)
			(size 2.1082 1.4478)
			(layers "F.Cu" "F.Mask" "F.Paste")
			(net "P12V_SSD2")
		)
		(pad "2" smd rect
			(at 0 1.392936)
			(size 2.1082 1.4478)
			(layers "F.Cu" "F.Mask" "F.Paste")
			(net "GND")
		)
	)
	(footprint ""
		(layer "F.Cu")
		(at 34.7218 -400.558 180)
		(property "Reference" "PC1242"
			(at 0 0 180)
			(layer "F.SilkS")
			(hide yes)
			(effects
				(font
					(size 1.27 1.27)
				)
			)
		)
		(property "Value" "SCD1U50V3KX-GP"
			(at 0 -2.8194 180)
			(unlocked yes)
			(layer "F.Fab")
			(hide yes)
			(effects
				(font
					(size 1.016 1.016)
					(thickness 0.1524)
				)
			)
		)
		(property "Device Type" "C603H36"
			(at 0 -4.3434 180)
			(unlocked yes)
			(layer "F.Fab")
			(hide yes)
			(effects
				(font
					(size 1.016 1.016)
					(thickness 0.1524)
				)
			)
		)
		(duplicate_pad_numbers_are_jumpers no)
		(fp_line
			(start 0.508 0)
			(end -0.508 0)
			(stroke
				(width 0.2032)
				(type default)
			)
			(layer "F.SilkS")
		)
		(fp_rect
			(start -0.5842 1.3335)
			(end 0.5842 -1.3335)
			(stroke
				(width 0)
				(type default)
			)
			(fill no)
			(layer "F.CrtYd")
		)
		(fp_rect
			(start -0.5842 1.3335)
			(end 0.5842 -1.3335)
			(stroke
				(width 0)
				(type default)
			)
			(fill no)
			(layer "F.Fab")
		)
		(pad "1" smd custom
			(at 0 -0.762 180)
			(size 0.2159 0.2159)
			(layers "F.Cu" "F.Mask" "F.Paste")
			(net "P12V_SSD6")
			(options
				(clearance outline)
				(anchor circle)
			)
			(primitives
				(gr_poly
					(pts
						(arc
							(start -0.3302 -0.4318)
							(mid -0.402042 -0.402042)
							(end -0.4318 -0.3302)
						)
						(arc
							(start -0.4318 0.3302)
							(mid -0.402042 0.402042)
							(end -0.3302 0.4318)
						)
						(arc
							(start 0.3302 0.4318)
							(mid 0.402042 0.402042)
							(end 0.4318 0.3302)
						)
						(arc
							(start 0.4318 -0.3302)
							(mid 0.402042 -0.402042)
							(end 0.3302 -0.4318)
						)
					)
					(width 0)
					(fill yes)
				)
			)
		)
		(pad "2" smd custom
			(at 0 0.762 180)
			(size 0.2159 0.2159)
			(layers "F.Cu" "F.Mask" "F.Paste")
			(net "GND")
			(options
				(clearance outline)
				(anchor circle)
			)
			(primitives
				(gr_poly
					(pts
						(arc
							(start -0.3302 -0.4318)
							(mid -0.402042 -0.402042)
							(end -0.4318 -0.3302)
						)
						(arc
							(start -0.4318 0.3302)
							(mid -0.402042 0.402042)
							(end -0.3302 0.4318)
						)
						(arc
							(start 0.3302 0.4318)
							(mid 0.402042 0.402042)
							(end 0.4318 0.3302)
						)
						(arc
							(start 0.4318 -0.3302)
							(mid 0.402042 -0.402042)
							(end 0.3302 -0.4318)
						)
					)
					(width 0)
					(fill yes)
				)
			)
		)
	)
	(footprint ""
		(layer "F.Cu")
		(at 91.948 -203.708)
		(property "Reference" "C9429"
			(at 0 0 0)
			(layer "F.SilkS")
			(hide yes)
			(effects
				(font
					(size 1.27 1.27)
				)
			)
		)
		(property "Value" "SCD1U16V2KX-3GP"
			(at 1.1811 -2.7051 0)
			(unlocked yes)
			(layer "F.Fab")
			(hide yes)
			(effects
				(font
					(size 1.016 1.016)
					(thickness 0.1524)
				)
			)
		)
		(property "Device Type" "C402H22"
			(at 1.1811 -4.2291 0)
			(unlocked yes)
			(layer "F.Fab")
			(hide yes)
			(effects
				(font
					(size 1.016 1.016)
					(thickness 0.1524)
				)
			)
		)
		(duplicate_pad_numbers_are_jumpers no)
		(fp_rect
			(start -0.4318 0.9525)
			(end 0.4318 -0.9525)
			(stroke
				(width 0)
				(type default)
			)
			(fill no)
			(layer "F.CrtYd")
		)
		(fp_rect
			(start -0.4318 0.9525)
			(end 0.4318 -0.9525)
			(stroke
				(width 0)
				(type default)
			)
			(fill no)
			(layer "F.Fab")
		)
		(pad "1" smd custom
			(at 0 -0.4445)
			(size 0.1524 0.1524)
			(layers "F.Cu" "F.Mask" "F.Paste")
			(net "VDD_DIFF_3")
			(options
				(clearance outline)
				(anchor circle)
			)
			(primitives
				(gr_poly
					(pts
						(arc
							(start 0.3048 -0.2032)
							(mid 0.275042 -0.275042)
							(end 0.2032 -0.3048)
						)
						(arc
							(start -0.2032 -0.3048)
							(mid -0.275042 -0.275042)
							(end -0.3048 -0.2032)
						)
						(arc
							(start -0.3048 0.2032)
							(mid -0.275042 0.275042)
							(end -0.2032 0.3048)
						)
						(arc
							(start 0.2032 0.3048)
							(mid 0.275042 0.275042)
							(end 0.3048 0.2032)
						)
					)
					(width 0)
					(fill yes)
				)
			)
		)
		(pad "2" smd custom
			(at 0 0.4445)
			(size 0.1524 0.1524)
			(layers "F.Cu" "F.Mask" "F.Paste")
			(net "GND")
			(options
				(clearance outline)
				(anchor circle)
			)
			(primitives
				(gr_poly
					(pts
						(arc
							(start 0.3048 -0.2032)
							(mid 0.275042 -0.275042)
							(end 0.2032 -0.3048)
						)
						(arc
							(start -0.2032 -0.3048)
							(mid -0.275042 -0.275042)
							(end -0.3048 -0.2032)
						)
						(arc
							(start -0.3048 0.2032)
							(mid -0.275042 0.275042)
							(end -0.2032 0.3048)
						)
						(arc
							(start 0.2032 0.3048)
							(mid 0.275042 0.275042)
							(end 0.3048 0.2032)
						)
					)
					(width 0)
					(fill yes)
				)
			)
		)
	)
	(footprint ""
		(layer "F.Cu")
		(at 37.6936 -212.8774)
		(property "Reference" "R580"
			(at 0 0 0)
			(layer "F.SilkS")
			(hide yes)
			(effects
				(font
					(size 1.27 1.27)
				)
			)
		)
		(property "Value" "300KR2F-GP"
			(at 0.064008 -3.993896 0)
			(unlocked yes)
			(layer "F.Fab")
			(hide yes)
			(effects
				(font
					(size 1.016 1.016)
					(thickness 0.1524)
				)
			)
		)
		(property "Device Type" "R402H16"
			(at 0.064008 -5.517896 0)
			(unlocked yes)
			(layer "F.Fab")
			(hide yes)
			(effects
				(font
					(size 1.016 1.016)
					(thickness 0.1524)
				)
			)
		)
		(duplicate_pad_numbers_are_jumpers no)
		(fp_line
			(start -0.508 -0.9398)
			(end -0.508 0.9398)
			(stroke
				(width 0.1524)
				(type default)
			)
			(layer "F.SilkS")
		)
		(fp_line
			(start 0.508 -0.9398)
			(end -0.508 -0.9398)
			(stroke
				(width 0.1524)
				(type default)
			)
			(layer "F.SilkS")
		)
		(fp_rect
			(start -0.508 0.9398)
			(end 0.508 -0.9398)
			(stroke
				(width 0)
				(type default)
			)
			(fill no)
			(layer "F.CrtYd")
		)
		(fp_rect
			(start -0.508 0.9398)
			(end 0.508 -0.9398)
			(stroke
				(width 0)
				(type default)
			)
			(fill no)
			(layer "F.Fab")
		)
		(pad "1" smd custom
			(at 0 -0.4445)
			(size 0.1397 0.1397)
			(layers "F.Cu" "F.Mask" "F.Paste")
			(net "SW_SSD12_N")
			(options
				(clearance outline)
				(anchor circle)
			)
			(primitives
				(gr_poly
					(pts
						(arc
							(start -0.1778 -0.2794)
							(mid -0.249642 -0.249642)
							(end -0.2794 -0.1778)
						)
						(arc
							(start -0.2794 0.1778)
							(mid -0.249642 0.249642)
							(end -0.1778 0.2794)
						)
						(arc
							(start 0.1778 0.2794)
							(mid 0.249642 0.249642)
							(end 0.2794 0.1778)
						)
						(arc
							(start 0.2794 -0.1778)
							(mid 0.249642 -0.249642)
							(end 0.1778 -0.2794)
						)
					)
					(width 0)
					(fill yes)
				)
			)
		)
		(pad "2" smd custom
			(at 0 0.4445)
			(size 0.1397 0.1397)
			(layers "F.Cu" "F.Mask" "F.Paste")
			(net "P12V")
			(options
				(clearance outline)
				(anchor circle)
			)
			(primitives
				(gr_poly
					(pts
						(arc
							(start -0.1778 -0.2794)
							(mid -0.249642 -0.249642)
							(end -0.2794 -0.1778)
						)
						(arc
							(start -0.2794 0.1778)
							(mid -0.249642 0.249642)
							(end -0.1778 0.2794)
						)
						(arc
							(start 0.1778 0.2794)
							(mid 0.249642 0.249642)
							(end 0.2794 0.1778)
						)
						(arc
							(start 0.2794 -0.1778)
							(mid 0.249642 -0.249642)
							(end 0.1778 -0.2794)
						)
					)
					(width 0)
					(fill yes)
				)
			)
		)
	)
	(footprint ""
		(layer "F.Cu")
		(at 77.5208 -305.6255 180)
		(property "Reference" "R9965"
			(at 0 0 180)
			(layer "F.SilkS")
			(hide yes)
			(effects
				(font
					(size 1.27 1.27)
				)
			)
		)
		(property "Value" "56R2F-1-GP"
			(at 0.064008 -3.993896 180)
			(unlocked yes)
			(layer "F.Fab")
			(hide yes)
			(effects
				(font
					(size 1.016 1.016)
					(thickness 0.1524)
				)
			)
		)
		(property "Device Type" "R402H16"
			(at 0.064008 -5.517896 180)
			(unlocked yes)
			(layer "F.Fab")
			(hide yes)
			(effects
				(font
					(size 1.016 1.016)
					(thickness 0.1524)
				)
			)
		)
		(duplicate_pad_numbers_are_jumpers no)
		(fp_line
			(start 0.508 -0.9398)
			(end -0.508 -0.9398)
			(stroke
				(width 0.1524)
				(type default)
			)
			(layer "F.SilkS")
		)
		(fp_line
			(start -0.508 -0.9398)
			(end -0.508 0.9398)
			(stroke
				(width 0.1524)
				(type default)
			)
			(layer "F.SilkS")
		)
		(fp_rect
			(start -0.508 0.9398)
			(end 0.508 -0.9398)
			(stroke
				(width 0)
				(type default)
			)
			(fill no)
			(layer "F.CrtYd")
		)
		(fp_rect
			(start -0.508 0.9398)
			(end 0.508 -0.9398)
			(stroke
				(width 0)
				(type default)
			)
			(fill no)
			(layer "F.Fab")
		)
		(pad "1" smd custom
			(at 0 -0.4445 180)
			(size 0.1397 0.1397)
			(layers "F.Cu" "F.Mask" "F.Paste")
			(net "PE_100M_CLK3_P")
			(options
				(clearance outline)
				(anchor circle)
			)
			(primitives
				(gr_poly
					(pts
						(arc
							(start -0.1778 -0.2794)
							(mid -0.249642 -0.249642)
							(end -0.2794 -0.1778)
						)
						(arc
							(start -0.2794 0.1778)
							(mid -0.249642 0.249642)
							(end -0.1778 0.2794)
						)
						(arc
							(start 0.1778 0.2794)
							(mid 0.249642 0.249642)
							(end 0.2794 0.1778)
						)
						(arc
							(start 0.2794 -0.1778)
							(mid 0.249642 -0.249642)
							(end 0.1778 -0.2794)
						)
					)
					(width 0)
					(fill yes)
				)
			)
		)
		(pad "2" smd custom
			(at 0 0.4445 180)
			(size 0.1397 0.1397)
			(layers "F.Cu" "F.Mask" "F.Paste")
			(net "GND")
			(options
				(clearance outline)
				(anchor circle)
			)
			(primitives
				(gr_poly
					(pts
						(arc
							(start -0.1778 -0.2794)
							(mid -0.249642 -0.249642)
							(end -0.2794 -0.1778)
						)
						(arc
							(start -0.2794 0.1778)
							(mid -0.249642 0.249642)
							(end -0.1778 0.2794)
						)
						(arc
							(start 0.1778 0.2794)
							(mid 0.249642 0.249642)
							(end 0.2794 0.1778)
						)
						(arc
							(start 0.2794 -0.1778)
							(mid 0.249642 -0.249642)
							(end 0.1778 -0.2794)
						)
					)
					(width 0)
					(fill yes)
				)
			)
		)
	)
)
